FILE_TYPE=LIBRARY_PARTS;
primitive 'ADC128D818CIMTXNOPB';
  pin
    'VREF':
      PIN_NUMBER='(1)';
      INPUT_LOAD='(-0.01,0.01)';
    'V+':
      PIN_NUMBER='(5)';
      PINUSE='POWER';
      NO_LOAD_CHECK='Both';
      NO_IO_CHECK='Both';
      NO_ASSERT_CHECK='TRUE';
      NO_DIR_CHECK='TRUE';
      ALLOW_CONNECT='TRUE';
    'A0':
      PIN_NUMBER='(7)';
      INPUT_LOAD='(-0.01,0.01)';
    'A1':
      PIN_NUMBER='(8)';
      INPUT_LOAD='(-0.01,0.01)';
    'IN7':
      PIN_NUMBER='(9)';
      INPUT_LOAD='(-0.01,0.01)';
    'IN6':
      PIN_NUMBER='(10)';
      INPUT_LOAD='(-0.01,0.01)';
    'IN5':
      PIN_NUMBER='(11)';
      INPUT_LOAD='(-0.01,0.01)';
    'IN4':
      PIN_NUMBER='(12)';
      INPUT_LOAD='(-0.01,0.01)';
    'IN3':
      PIN_NUMBER='(13)';
      INPUT_LOAD='(-0.01,0.01)';
    'IN2':
      PIN_NUMBER='(14)';
      INPUT_LOAD='(-0.01,0.01)';
    'IN1':
      PIN_NUMBER='(15)';
      INPUT_LOAD='(-0.01,0.01)';
    'IN0':
      PIN_NUMBER='(16)';
      INPUT_LOAD='(-0.01,0.01)';
    'SDA':
      PIN_NUMBER='(2)';
      BIDIRECTIONAL='TRUE';
      INPUT_LOAD='(-0.01,0.01)';
      OUTPUT_LOAD='(1.0,-1.0)';
    'SCL':
      PIN_NUMBER='(3)';
      INPUT_LOAD='(-0.01,0.01)';
    'GND':
      PIN_NUMBER='(4)';
      PINUSE='POWER';
      NO_LOAD_CHECK='Both';
      NO_IO_CHECK='Both';
      NO_ASSERT_CHECK='TRUE';
      NO_DIR_CHECK='TRUE';
      ALLOW_CONNECT='TRUE';
    'INT#':
      PIN_NUMBER='(6)';
      OUTPUT_LOAD='(1.0,-1.0)';
  end_pin;
  body
    PART_NAME='ADC128D818CIMTXNOPB';
    BODY_NAME='ADC128D818CIMTXNOPB';
    PHYS_DES_PREFIX='U';
    CLASS='IC';
  end_body;
end_primitive;

END.
